(kicad_pcb
	(version 20260206)
	(generator "pcbnew")
	(generator_version "10.0")
	(general
		(thickness 1.6)
		(legacy_teardrops no)
	)
	(paper "A4")
	(title_block
		(title "01162023_DA0F0TEBIF0_F0T_Expander_BD_F_brd_V02_OCP.brd")
		(comment 1 "Grand Teton / footprints 5709-5715 of 9728")
	)
	(layers
		(0 "F.Cu" signal "TOP")
		(4 "In1.Cu" signal "GND")
		(6 "In2.Cu" signal "VCC")
		(8 "In3.Cu" signal "VCC1")
		(10 "In4.Cu" signal "GND1")
		(12 "In5.Cu" signal "IN1")
		(14 "In6.Cu" signal "GND2")
		(16 "In7.Cu" signal "IN2")
		(18 "In8.Cu" signal "GND3")
		(20 "In9.Cu" signal "IN3")
		(22 "In10.Cu" signal "GND4")
		(24 "In11.Cu" signal "IN4")
		(26 "In12.Cu" signal "GND5")
		(28 "In13.Cu" signal "IN5")
		(30 "In14.Cu" signal "GND6")
		(32 "In15.Cu" signal "IN6")
		(34 "In16.Cu" signal "GND7")
		(2 "B.Cu" signal "BOTTOM")
		(9 "F.Adhes" user "F.Adhesive")
		(11 "B.Adhes" user "B.Adhesive")
		(13 "F.Paste" user "Package Geometry/Pastemask Top")
		(15 "B.Paste" user "Package Geometry/Pastemask Bottom")
		(5 "F.SilkS" user "Ref Des/Silkscreen Top")
		(7 "B.SilkS" user "Ref Des/Silkscreen Bottom")
		(1 "F.Mask" user "Board Geometry/Soldermask Top")
		(3 "B.Mask" user "Board Geometry/Soldermask Bottom")
		(17 "Dwgs.User" user "User.Drawings")
		(19 "Cmts.User" user "User.Comments")
		(21 "Eco1.User" user "User.Eco1")
		(23 "Eco2.User" user "User.Eco2")
		(25 "Edge.Cuts" user "Board Geometry/Outline")
		(27 "Margin" user)
		(31 "F.CrtYd" user "Package Geometry/Place Bound Top")
		(29 "B.CrtYd" user "Package Geometry/Place Bound Bottom")
		(35 "F.Fab" user "Ref Des/Assembly Top")
		(33 "B.Fab" user "Ref Des/Assembly Bottom")
	)
	(footprint ""
		(layer "F.Cu")
		(at 304.714402 -66.32194 90)
		(property "Reference" "R6000"
			(at 0 0 90)
			(layer "F.SilkS")
			(hide yes)
			(effects
				(font
					(size 1.27 1.27)
				)
			)
		)
		(property "Value" ""
			(at 0 0 90)
			(layer "F.Fab")
			(effects
				(font
					(size 1.27 1.27)
				)
			)
		)
		(duplicate_pad_numbers_are_jumpers no)
		(fp_line
			(start 0.7874 -0.4064)
			(end 0.7874 0.4064)
			(stroke
				(width 0.1524)
				(type default)
			)
			(layer "F.SilkS")
		)
		(fp_line
			(start -0.7874 -0.4064)
			(end 0.7874 -0.4064)
			(stroke
				(width 0.1524)
				(type default)
			)
			(layer "F.SilkS")
		)
		(fp_line
			(start 0.7874 0.4064)
			(end -0.7874 0.4064)
			(stroke
				(width 0.1524)
				(type default)
			)
			(layer "F.SilkS")
		)
		(fp_line
			(start -0.7874 0.4064)
			(end -0.7874 -0.4064)
			(stroke
				(width 0.1524)
				(type default)
			)
			(layer "F.SilkS")
		)
		(fp_line
			(start -0.12065 -0.305054)
			(end -0.12065 -0.2794)
			(stroke
				(width 0.1)
				(type default)
			)
			(layer "F.Fab")
		)
		(fp_line
			(start -0.67945 -0.305054)
			(end -0.12065 -0.305054)
			(stroke
				(width 0.1)
				(type default)
			)
			(layer "F.Fab")
		)
		(fp_line
			(start 0.67945 -0.3048)
			(end 0.67945 0.3048)
			(stroke
				(width 0.1)
				(type default)
			)
			(layer "F.Fab")
		)
		(fp_line
			(start 0.12065 -0.3048)
			(end 0.67945 -0.3048)
			(stroke
				(width 0.1)
				(type default)
			)
			(layer "F.Fab")
		)
		(fp_line
			(start 0.12065 -0.2794)
			(end 0.12065 -0.3048)
			(stroke
				(width 0.1)
				(type default)
			)
			(layer "F.Fab")
		)
		(fp_line
			(start -0.12065 -0.2794)
			(end 0.12065 -0.2794)
			(stroke
				(width 0.1)
				(type default)
			)
			(layer "F.Fab")
		)
		(fp_line
			(start 0.120396 0.2794)
			(end -0.12065 0.2794)
			(stroke
				(width 0.1)
				(type default)
			)
			(layer "F.Fab")
		)
		(fp_line
			(start -0.12065 0.2794)
			(end -0.12065 0.3048)
			(stroke
				(width 0.1)
				(type default)
			)
			(layer "F.Fab")
		)
		(fp_line
			(start 0.67945 0.3048)
			(end 0.120396 0.3048)
			(stroke
				(width 0.1)
				(type default)
			)
			(layer "F.Fab")
		)
		(fp_line
			(start 0.120396 0.3048)
			(end 0.120396 0.2794)
			(stroke
				(width 0.1)
				(type default)
			)
			(layer "F.Fab")
		)
		(fp_line
			(start -0.12065 0.3048)
			(end -0.67945 0.3048)
			(stroke
				(width 0.1)
				(type default)
			)
			(layer "F.Fab")
		)
		(fp_line
			(start -0.67945 0.3048)
			(end -0.67945 -0.305054)
			(stroke
				(width 0.1)
				(type default)
			)
			(layer "F.Fab")
		)
		(pad "1" smd circle
			(at -0.40005 0 90)
			(size 0 0)
			(layers "F.Cu" "F.Mask" "F.Paste")
			(net "SSD10_PWR_EN_R")
		)
		(pad "2" smd circle
			(at 0.40005 0 90)
			(size 0 0)
			(layers "F.Cu" "F.Mask" "F.Paste")
			(net "P12V_SSD10_CO_EN")
		)
	)
	(footprint ""
		(layer "F.Cu")
		(at 357.549196 -279.486868 -90)
		(property "Reference" "PC186"
			(at 0 0 270)
			(layer "F.SilkS")
			(hide yes)
			(effects
				(font
					(size 1.27 1.27)
				)
			)
		)
		(property "Value" ""
			(at 0 0 270)
			(layer "F.Fab")
			(effects
				(font
					(size 1.27 1.27)
				)
			)
		)
		(duplicate_pad_numbers_are_jumpers no)
		(fp_line
			(start -0.7874 0.4064)
			(end -0.7874 -0.4064)
			(stroke
				(width 0.1524)
				(type default)
			)
			(layer "F.SilkS")
		)
		(fp_line
			(start 0.7874 0.4064)
			(end -0.7874 0.4064)
			(stroke
				(width 0.1524)
				(type default)
			)
			(layer "F.SilkS")
		)
		(fp_line
			(start -0.7874 -0.4064)
			(end 0.7874 -0.4064)
			(stroke
				(width 0.1524)
				(type default)
			)
			(layer "F.SilkS")
		)
		(fp_line
			(start 0.7874 -0.4064)
			(end 0.7874 0.4064)
			(stroke
				(width 0.1524)
				(type default)
			)
			(layer "F.SilkS")
		)
		(fp_line
			(start -0.67945 0.3048)
			(end -0.67945 -0.305054)
			(stroke
				(width 0.1)
				(type default)
			)
			(layer "F.Fab")
		)
		(fp_line
			(start -0.12065 0.3048)
			(end -0.67945 0.3048)
			(stroke
				(width 0.1)
				(type default)
			)
			(layer "F.Fab")
		)
		(fp_line
			(start 0.120396 0.3048)
			(end 0.120396 0.2794)
			(stroke
				(width 0.1)
				(type default)
			)
			(layer "F.Fab")
		)
		(fp_line
			(start 0.67945 0.3048)
			(end 0.120396 0.3048)
			(stroke
				(width 0.1)
				(type default)
			)
			(layer "F.Fab")
		)
		(fp_line
			(start -0.12065 0.2794)
			(end -0.12065 0.3048)
			(stroke
				(width 0.1)
				(type default)
			)
			(layer "F.Fab")
		)
		(fp_line
			(start 0.120396 0.2794)
			(end -0.12065 0.2794)
			(stroke
				(width 0.1)
				(type default)
			)
			(layer "F.Fab")
		)
		(fp_line
			(start -0.12065 -0.2794)
			(end 0.12065 -0.2794)
			(stroke
				(width 0.1)
				(type default)
			)
			(layer "F.Fab")
		)
		(fp_line
			(start 0.12065 -0.2794)
			(end 0.12065 -0.3048)
			(stroke
				(width 0.1)
				(type default)
			)
			(layer "F.Fab")
		)
		(fp_line
			(start 0.12065 -0.3048)
			(end 0.67945 -0.3048)
			(stroke
				(width 0.1)
				(type default)
			)
			(layer "F.Fab")
		)
		(fp_line
			(start 0.67945 -0.3048)
			(end 0.67945 0.3048)
			(stroke
				(width 0.1)
				(type default)
			)
			(layer "F.Fab")
		)
		(fp_line
			(start -0.67945 -0.305054)
			(end -0.12065 -0.305054)
			(stroke
				(width 0.1)
				(type default)
			)
			(layer "F.Fab")
		)
		(fp_line
			(start -0.12065 -0.305054)
			(end -0.12065 -0.2794)
			(stroke
				(width 0.1)
				(type default)
			)
			(layer "F.Fab")
		)
		(pad "1" smd circle
			(at -0.40005 0 270)
			(size 0 0)
			(layers "F.Cu" "F.Mask" "F.Paste")
			(net "P0V8_PEX2_VREF")
		)
		(pad "2" smd circle
			(at 0.40005 0 270)
			(size 0 0)
			(layers "F.Cu" "F.Mask" "F.Paste")
			(net "GND")
		)
	)
	(footprint ""
		(layer "F.Cu")
		(at 60.12053 -26.666444 -90)
		(property "Reference" "R4057"
			(at 0 0 270)
			(layer "F.SilkS")
			(hide yes)
			(effects
				(font
					(size 1.27 1.27)
				)
			)
		)
		(property "Value" ""
			(at 0 0 270)
			(layer "F.Fab")
			(effects
				(font
					(size 1.27 1.27)
				)
			)
		)
		(duplicate_pad_numbers_are_jumpers no)
		(fp_line
			(start -0.7874 0.4064)
			(end -0.7874 -0.4064)
			(stroke
				(width 0.1524)
				(type default)
			)
			(layer "F.SilkS")
		)
		(fp_line
			(start 0.7874 0.4064)
			(end -0.7874 0.4064)
			(stroke
				(width 0.1524)
				(type default)
			)
			(layer "F.SilkS")
		)
		(fp_line
			(start -0.7874 -0.4064)
			(end 0.7874 -0.4064)
			(stroke
				(width 0.1524)
				(type default)
			)
			(layer "F.SilkS")
		)
		(fp_line
			(start 0.7874 -0.4064)
			(end 0.7874 0.4064)
			(stroke
				(width 0.1524)
				(type default)
			)
			(layer "F.SilkS")
		)
		(fp_line
			(start -0.67945 0.3048)
			(end -0.67945 -0.305054)
			(stroke
				(width 0.1)
				(type default)
			)
			(layer "F.Fab")
		)
		(fp_line
			(start -0.12065 0.3048)
			(end -0.67945 0.3048)
			(stroke
				(width 0.1)
				(type default)
			)
			(layer "F.Fab")
		)
		(fp_line
			(start 0.120396 0.3048)
			(end 0.120396 0.2794)
			(stroke
				(width 0.1)
				(type default)
			)
			(layer "F.Fab")
		)
		(fp_line
			(start 0.67945 0.3048)
			(end 0.120396 0.3048)
			(stroke
				(width 0.1)
				(type default)
			)
			(layer "F.Fab")
		)
		(fp_line
			(start -0.12065 0.2794)
			(end -0.12065 0.3048)
			(stroke
				(width 0.1)
				(type default)
			)
			(layer "F.Fab")
		)
		(fp_line
			(start 0.120396 0.2794)
			(end -0.12065 0.2794)
			(stroke
				(width 0.1)
				(type default)
			)
			(layer "F.Fab")
		)
		(fp_line
			(start -0.12065 -0.2794)
			(end 0.12065 -0.2794)
			(stroke
				(width 0.1)
				(type default)
			)
			(layer "F.Fab")
		)
		(fp_line
			(start 0.12065 -0.2794)
			(end 0.12065 -0.3048)
			(stroke
				(width 0.1)
				(type default)
			)
			(layer "F.Fab")
		)
		(fp_line
			(start 0.12065 -0.3048)
			(end 0.67945 -0.3048)
			(stroke
				(width 0.1)
				(type default)
			)
			(layer "F.Fab")
		)
		(fp_line
			(start 0.67945 -0.3048)
			(end 0.67945 0.3048)
			(stroke
				(width 0.1)
				(type default)
			)
			(layer "F.Fab")
		)
		(fp_line
			(start -0.67945 -0.305054)
			(end -0.12065 -0.305054)
			(stroke
				(width 0.1)
				(type default)
			)
			(layer "F.Fab")
		)
		(fp_line
			(start -0.12065 -0.305054)
			(end -0.12065 -0.2794)
			(stroke
				(width 0.1)
				(type default)
			)
			(layer "F.Fab")
		)
		(pad "1" smd circle
			(at -0.40005 0 270)
			(size 0 0)
			(layers "F.Cu" "F.Mask" "F.Paste")
			(net "PRSNT_SSD2_R_N")
		)
		(pad "2" smd circle
			(at 0.40005 0 270)
			(size 0 0)
			(layers "F.Cu" "F.Mask" "F.Paste")
			(net "PRSNT_SSD2_N")
		)
	)
	(footprint ""
		(layer "F.Cu")
		(at 278.634444 -33.631886 180)
		(property "Reference" "C496"
			(at 0 0 180)
			(layer "F.SilkS")
			(hide yes)
			(effects
				(font
					(size 1.27 1.27)
				)
			)
		)
		(property "Value" ""
			(at 0 0 180)
			(layer "F.Fab")
			(effects
				(font
					(size 1.27 1.27)
				)
			)
		)
		(duplicate_pad_numbers_are_jumpers no)
		(fp_line
			(start 0.299974 0.150114)
			(end -0.299974 0.150114)
			(stroke
				(width 0.1)
				(type default)
			)
			(layer "F.Fab")
		)
		(fp_line
			(start 0.299974 -0.150114)
			(end 0.299974 0.150114)
			(stroke
				(width 0.1)
				(type default)
			)
			(layer "F.Fab")
		)
		(fp_line
			(start -0.299974 0.150114)
			(end -0.299974 -0.150114)
			(stroke
				(width 0.1)
				(type default)
			)
			(layer "F.Fab")
		)
		(fp_line
			(start -0.299974 -0.150114)
			(end 0.299974 -0.150114)
			(stroke
				(width 0.1)
				(type default)
			)
			(layer "F.Fab")
		)
		(pad "1" smd rect
			(at -0.2667 0 180)
			(size 0.3048 0.381)
			(layers "F.Cu" "F.Mask" "F.Paste")
			(net "P5E_PEX2_STN2_TX_DN<43>")
		)
		(pad "2" smd rect
			(at 0.2667 0 180)
			(size 0.3048 0.381)
			(layers "F.Cu" "F.Mask" "F.Paste")
			(net "P5E_PEX2_STN2_TX_C_DN<43>")
		)
	)
	(footprint ""
		(layer "F.Cu")
		(at 234.64266 -204.44206 90)
		(property "Reference" "R5534"
			(at 0 0 90)
			(layer "F.SilkS")
			(hide yes)
			(effects
				(font
					(size 1.27 1.27)
				)
			)
		)
		(property "Value" ""
			(at 0 0 90)
			(layer "F.Fab")
			(effects
				(font
					(size 1.27 1.27)
				)
			)
		)
		(duplicate_pad_numbers_are_jumpers no)
		(fp_line
			(start 0.7874 -0.4064)
			(end 0.7874 0.4064)
			(stroke
				(width 0.1524)
				(type default)
			)
			(layer "F.SilkS")
		)
		(fp_line
			(start -0.7874 -0.4064)
			(end 0.7874 -0.4064)
			(stroke
				(width 0.1524)
				(type default)
			)
			(layer "F.SilkS")
		)
		(fp_line
			(start 0.7874 0.4064)
			(end -0.7874 0.4064)
			(stroke
				(width 0.1524)
				(type default)
			)
			(layer "F.SilkS")
		)
		(fp_line
			(start -0.7874 0.4064)
			(end -0.7874 -0.4064)
			(stroke
				(width 0.1524)
				(type default)
			)
			(layer "F.SilkS")
		)
		(fp_line
			(start -0.12065 -0.305054)
			(end -0.12065 -0.2794)
			(stroke
				(width 0.1)
				(type default)
			)
			(layer "F.Fab")
		)
		(fp_line
			(start -0.67945 -0.305054)
			(end -0.12065 -0.305054)
			(stroke
				(width 0.1)
				(type default)
			)
			(layer "F.Fab")
		)
		(fp_line
			(start 0.67945 -0.3048)
			(end 0.67945 0.3048)
			(stroke
				(width 0.1)
				(type default)
			)
			(layer "F.Fab")
		)
		(fp_line
			(start 0.12065 -0.3048)
			(end 0.67945 -0.3048)
			(stroke
				(width 0.1)
				(type default)
			)
			(layer "F.Fab")
		)
		(fp_line
			(start 0.12065 -0.2794)
			(end 0.12065 -0.3048)
			(stroke
				(width 0.1)
				(type default)
			)
			(layer "F.Fab")
		)
		(fp_line
			(start -0.12065 -0.2794)
			(end 0.12065 -0.2794)
			(stroke
				(width 0.1)
				(type default)
			)
			(layer "F.Fab")
		)
		(fp_line
			(start 0.120396 0.2794)
			(end -0.12065 0.2794)
			(stroke
				(width 0.1)
				(type default)
			)
			(layer "F.Fab")
		)
		(fp_line
			(start -0.12065 0.2794)
			(end -0.12065 0.3048)
			(stroke
				(width 0.1)
				(type default)
			)
			(layer "F.Fab")
		)
		(fp_line
			(start 0.67945 0.3048)
			(end 0.120396 0.3048)
			(stroke
				(width 0.1)
				(type default)
			)
			(layer "F.Fab")
		)
		(fp_line
			(start 0.120396 0.3048)
			(end 0.120396 0.2794)
			(stroke
				(width 0.1)
				(type default)
			)
			(layer "F.Fab")
		)
		(fp_line
			(start -0.12065 0.3048)
			(end -0.67945 0.3048)
			(stroke
				(width 0.1)
				(type default)
			)
			(layer "F.Fab")
		)
		(fp_line
			(start -0.67945 0.3048)
			(end -0.67945 -0.305054)
			(stroke
				(width 0.1)
				(type default)
			)
			(layer "F.Fab")
		)
		(pad "1" smd circle
			(at -0.40005 0 90)
			(size 0 0)
			(layers "F.Cu" "F.Mask" "F.Paste")
			(net "P3V3_AUX")
		)
		(pad "2" smd circle
			(at 0.40005 0 90)
			(size 0 0)
			(layers "F.Cu" "F.Mask" "F.Paste")
			(net "SPI_BIC1_MISO")
		)
	)
	(footprint ""
		(layer "F.Cu")
		(at 299.58919 -213.523068 -90)
		(property "Reference" "R3398"
			(at 0 0 270)
			(layer "F.SilkS")
			(hide yes)
			(effects
				(font
					(size 1.27 1.27)
				)
			)
		)
		(property "Value" ""
			(at 0 0 270)
			(layer "F.Fab")
			(effects
				(font
					(size 1.27 1.27)
				)
			)
		)
		(duplicate_pad_numbers_are_jumpers no)
		(fp_line
			(start -0.7874 0.4064)
			(end -0.7874 -0.4064)
			(stroke
				(width 0.1524)
				(type default)
			)
			(layer "F.SilkS")
		)
		(fp_line
			(start 0.7874 0.4064)
			(end -0.7874 0.4064)
			(stroke
				(width 0.1524)
				(type default)
			)
			(layer "F.SilkS")
		)
		(fp_line
			(start -0.7874 -0.4064)
			(end 0.7874 -0.4064)
			(stroke
				(width 0.1524)
				(type default)
			)
			(layer "F.SilkS")
		)
		(fp_line
			(start 0.7874 -0.4064)
			(end 0.7874 0.4064)
			(stroke
				(width 0.1524)
				(type default)
			)
			(layer "F.SilkS")
		)
		(fp_line
			(start -0.67945 0.3048)
			(end -0.67945 -0.305054)
			(stroke
				(width 0.1)
				(type default)
			)
			(layer "F.Fab")
		)
		(fp_line
			(start -0.12065 0.3048)
			(end -0.67945 0.3048)
			(stroke
				(width 0.1)
				(type default)
			)
			(layer "F.Fab")
		)
		(fp_line
			(start 0.120396 0.3048)
			(end 0.120396 0.2794)
			(stroke
				(width 0.1)
				(type default)
			)
			(layer "F.Fab")
		)
		(fp_line
			(start 0.67945 0.3048)
			(end 0.120396 0.3048)
			(stroke
				(width 0.1)
				(type default)
			)
			(layer "F.Fab")
		)
		(fp_line
			(start -0.12065 0.2794)
			(end -0.12065 0.3048)
			(stroke
				(width 0.1)
				(type default)
			)
			(layer "F.Fab")
		)
		(fp_line
			(start 0.120396 0.2794)
			(end -0.12065 0.2794)
			(stroke
				(width 0.1)
				(type default)
			)
			(layer "F.Fab")
		)
		(fp_line
			(start -0.12065 -0.2794)
			(end 0.12065 -0.2794)
			(stroke
				(width 0.1)
				(type default)
			)
			(layer "F.Fab")
		)
		(fp_line
			(start 0.12065 -0.2794)
			(end 0.12065 -0.3048)
			(stroke
				(width 0.1)
				(type default)
			)
			(layer "F.Fab")
		)
		(fp_line
			(start 0.12065 -0.3048)
			(end 0.67945 -0.3048)
			(stroke
				(width 0.1)
				(type default)
			)
			(layer "F.Fab")
		)
		(fp_line
			(start 0.67945 -0.3048)
			(end 0.67945 0.3048)
			(stroke
				(width 0.1)
				(type default)
			)
			(layer "F.Fab")
		)
		(fp_line
			(start -0.67945 -0.305054)
			(end -0.12065 -0.305054)
			(stroke
				(width 0.1)
				(type default)
			)
			(layer "F.Fab")
		)
		(fp_line
			(start -0.12065 -0.305054)
			(end -0.12065 -0.2794)
			(stroke
				(width 0.1)
				(type default)
			)
			(layer "F.Fab")
		)
		(pad "1" smd circle
			(at -0.40005 0 270)
			(size 0 0)
			(layers "F.Cu" "F.Mask" "F.Paste")
			(net "SPI_BIC1_CS0_LS23_R2_N")
		)
		(pad "2" smd circle
			(at 0.40005 0 270)
			(size 0 0)
			(layers "F.Cu" "F.Mask" "F.Paste")
			(net "SPI_BIC1_CS0_LS23_R_N")
		)
	)
	(footprint ""
		(layer "F.Cu")
		(at 217.227912 -211.193126 180)
		(property "Reference" "R6412"
			(at 0 0 180)
			(layer "F.SilkS")
			(hide yes)
			(effects
				(font
					(size 1.27 1.27)
				)
			)
		)
		(property "Value" ""
			(at 0 0 180)
			(layer "F.Fab")
			(effects
				(font
					(size 1.27 1.27)
				)
			)
		)
		(duplicate_pad_numbers_are_jumpers no)
		(fp_line
			(start 0.7874 0.4064)
			(end -0.7874 0.4064)
			(stroke
				(width 0.1524)
				(type default)
			)
			(layer "F.SilkS")
		)
		(fp_line
			(start 0.7874 -0.4064)
			(end 0.7874 0.4064)
			(stroke
				(width 0.1524)
				(type default)
			)
			(layer "F.SilkS")
		)
		(fp_line
			(start -0.7874 0.4064)
			(end -0.7874 -0.4064)
			(stroke
				(width 0.1524)
				(type default)
			)
			(layer "F.SilkS")
		)
		(fp_line
			(start -0.7874 -0.4064)
			(end 0.7874 -0.4064)
			(stroke
				(width 0.1524)
				(type default)
			)
			(layer "F.SilkS")
		)
		(fp_line
			(start 0.67945 0.3048)
			(end 0.120396 0.3048)
			(stroke
				(width 0.1)
				(type default)
			)
			(layer "F.Fab")
		)
		(fp_line
			(start 0.67945 -0.3048)
			(end 0.67945 0.3048)
			(stroke
				(width 0.1)
				(type default)
			)
			(layer "F.Fab")
		)
		(fp_line
			(start 0.12065 -0.2794)
			(end 0.12065 -0.3048)
			(stroke
				(width 0.1)
				(type default)
			)
			(layer "F.Fab")
		)
		(fp_line
			(start 0.12065 -0.3048)
			(end 0.67945 -0.3048)
			(stroke
				(width 0.1)
				(type default)
			)
			(layer "F.Fab")
		)
		(fp_line
			(start 0.120396 0.3048)
			(end 0.120396 0.2794)
			(stroke
				(width 0.1)
				(type default)
			)
			(layer "F.Fab")
		)
		(fp_line
			(start 0.120396 0.2794)
			(end -0.12065 0.2794)
			(stroke
				(width 0.1)
				(type default)
			)
			(layer "F.Fab")
		)
		(fp_line
			(start -0.12065 0.3048)
			(end -0.67945 0.3048)
			(stroke
				(width 0.1)
				(type default)
			)
			(layer "F.Fab")
		)
		(fp_line
			(start -0.12065 0.2794)
			(end -0.12065 0.3048)
			(stroke
				(width 0.1)
				(type default)
			)
			(layer "F.Fab")
		)
		(fp_line
			(start -0.12065 -0.2794)
			(end 0.12065 -0.2794)
			(stroke
				(width 0.1)
				(type default)
			)
			(layer "F.Fab")
		)
		(fp_line
			(start -0.12065 -0.305054)
			(end -0.12065 -0.2794)
			(stroke
				(width 0.1)
				(type default)
			)
			(layer "F.Fab")
		)
		(fp_line
			(start -0.67945 0.3048)
			(end -0.67945 -0.305054)
			(stroke
				(width 0.1)
				(type default)
			)
			(layer "F.Fab")
		)
		(fp_line
			(start -0.67945 -0.305054)
			(end -0.12065 -0.305054)
			(stroke
				(width 0.1)
				(type default)
			)
			(layer "F.Fab")
		)
		(pad "1" smd circle
			(at -0.40005 0 180)
			(size 0 0)
			(layers "F.Cu" "F.Mask" "F.Paste")
			(net "RST_BIC_I2C9_SSD_MUX0_N")
		)
		(pad "2" smd circle
			(at 0.40005 0 180)
			(size 0 0)
			(layers "F.Cu" "F.Mask" "F.Paste")
			(net "P3V3_AUX")
		)
	)
)
